(kicad_pcb
	(version 20260206)
	(generator "pcbnew")
	(generator_version "10.0")
	(general
		(thickness 1.6)
		(legacy_teardrops no)
	)
	(paper "A4")
	(title_block
		(title "Wiwynn_Tioga_Pass_MB.brd")
		(comment 1 "Tioga Pass / footprints 3744-3750 of 4770")
	)
	(layers
		(0 "F.Cu" signal "TOP")
		(4 "In1.Cu" signal "L2GND")
		(6 "In2.Cu" signal "L3")
		(8 "In3.Cu" signal "L4GND")
		(10 "In4.Cu" signal "L5")
		(12 "In5.Cu" signal "L6GND")
		(14 "In6.Cu" signal "L7VCC")
		(16 "In7.Cu" signal "L8VCC")
		(18 "In8.Cu" signal "L9GND")
		(20 "In9.Cu" signal "L10")
		(22 "In10.Cu" signal "L11GND")
		(24 "In11.Cu" signal "L12")
		(26 "In12.Cu" signal "L13GND")
		(2 "B.Cu" signal "BOTTOM")
		(9 "F.Adhes" user "F.Adhesive")
		(11 "B.Adhes" user "B.Adhesive")
		(13 "F.Paste" user "Package Geometry/Pastemask Top")
		(15 "B.Paste" user "Package Geometry/Pastemask Bottom")
		(5 "F.SilkS" user "Ref Des/Silkscreen Top")
		(7 "B.SilkS" user "Ref Des/Silkscreen Bottom")
		(1 "F.Mask" user "Board Geometry/Soldermask Top")
		(3 "B.Mask" user "Board Geometry/Soldermask Bottom")
		(17 "Dwgs.User" user "User.Drawings")
		(19 "Cmts.User" user "User.Comments")
		(21 "Eco1.User" user "User.Eco1")
		(23 "Eco2.User" user "User.Eco2")
		(25 "Edge.Cuts" user "Board Geometry/Outline")
		(27 "Margin" user)
		(31 "F.CrtYd" user "Package Geometry/Place Bound Top")
		(29 "B.CrtYd" user "Package Geometry/Place Bound Bottom")
		(35 "F.Fab" user "Ref Des/Assembly Top")
		(33 "B.Fab" user "Ref Des/Assembly Bottom")
	)
	(footprint ""
		(layer "B.Cu")
		(at 341.666068 -77.694536)
		(property "Reference" "C3P14"
			(at 0 0 0)
			(layer "B.SilkS")
			(hide yes)
			(effects
				(font
					(size 1.27 1.27)
				)
				(justify mirror)
			)
		)
		(property "Value" ""
			(at 0 0 0)
			(layer "B.Fab")
			(effects
				(font
					(size 1.27 1.27)
				)
				(justify mirror)
			)
		)
		(duplicate_pad_numbers_are_jumpers no)
		(fp_poly
			(pts
				(xy -0.3048 -0.1016) (xy -0.3048 0.9906) (xy 0.3048 0.9906) (xy 0.3048 -0.1016)
			)
			(stroke
				(width 0)
				(type default)
			)
			(fill no)
			(layer "B.CrtYd")
		)
		(fp_line
			(start -0.3048 -0.1016)
			(end 0.3048 -0.1016)
			(stroke
				(width 0.1)
				(type default)
			)
			(layer "B.Fab")
		)
		(fp_line
			(start -0.3048 0.9906)
			(end -0.3048 -0.1016)
			(stroke
				(width 0.1)
				(type default)
			)
			(layer "B.Fab")
		)
		(fp_line
			(start 0.3048 -0.1016)
			(end 0.3048 0.9906)
			(stroke
				(width 0.1)
				(type default)
			)
			(layer "B.Fab")
		)
		(fp_line
			(start 0.3048 0.9906)
			(end -0.3048 0.9906)
			(stroke
				(width 0.1)
				(type default)
			)
			(layer "B.Fab")
		)
		(pad "1" smd rect
			(at 0 0 180)
			(size 0.508 0.508)
			(layers "B.Cu" "B.Mask" "B.Paste")
			(net "P3E_CPU0_PE1_SS_TXP<1>")
		)
		(pad "2" smd rect
			(at 0 0.889 180)
			(size 0.508 0.508)
			(layers "B.Cu" "B.Mask" "B.Paste")
			(net "P3E_CPU0_PE1_SS_C_TXP<1>")
		)
		(zone
			(layer "B.Cu")
			(hatch none 0.5)
			(connect_pads
				(clearance 0)
			)
			(min_thickness 0.25)
			(keepout
				(tracks allowed)
				(vias not_allowed)
				(pads allowed)
				(copperpour not_allowed)
				(footprints allowed)
			)
			(placement
				(enabled no)
				(sheetname "")
			)
			(fill
				(thermal_gap 0.5)
				(thermal_bridge_width 0.5)
				(island_removal_mode 0)
			)
			(polygon
				(pts
					(xy 341.920068 -77.440536) (xy 341.412068 -77.440536) (xy 341.412068 -77.059536) (xy 341.920068 -77.059536)
				)
			)
		)
		(zone
			(layer "B.Cu")
			(hatch none 0.5)
			(connect_pads
				(clearance 0)
			)
			(min_thickness 0.25)
			(keepout
				(tracks not_allowed)
				(vias allowed)
				(pads allowed)
				(copperpour not_allowed)
				(footprints allowed)
			)
			(placement
				(enabled no)
				(sheetname "")
			)
			(fill
				(thermal_gap 0.5)
				(thermal_bridge_width 0.5)
				(island_removal_mode 0)
			)
			(polygon
				(pts
					(xy 341.920068 -77.059536) (xy 341.412068 -77.059536) (xy 341.412068 -77.440536) (xy 341.920068 -77.440536)
				)
			)
		)
	)
	(footprint ""
		(layer "B.Cu")
		(at 210.847432 -73.279 -90)
		(property "Reference" "C6P18"
			(at -1.87833 -3.909568 0)
			(unlocked yes)
			(layer "B.SilkS")
			(effects
				(font
					(size 0.7874 0.5842)
					(thickness 0.1524)
				)
				(justify mirror)
			)
		)
		(property "Value" ""
			(at 0 0 90)
			(layer "B.Fab")
			(effects
				(font
					(size 1.27 1.27)
				)
				(justify mirror)
			)
		)
		(duplicate_pad_numbers_are_jumpers no)
		(fp_line
			(start -2.286 7.366)
			(end -1.600708 7.366)
			(stroke
				(width 0.1524)
				(type default)
			)
			(layer "B.SilkS")
		)
		(fp_line
			(start -2.286 7.366)
			(end -2.286 1.63195)
			(stroke
				(width 0.1524)
				(type default)
			)
			(layer "B.SilkS")
		)
		(fp_line
			(start 2.286 7.366)
			(end 1.60147 7.366)
			(stroke
				(width 0.1524)
				(type default)
			)
			(layer "B.SilkS")
		)
		(fp_line
			(start 2.286 7.366)
			(end 2.286 1.632712)
			(stroke
				(width 0.1524)
				(type default)
			)
			(layer "B.SilkS")
		)
		(fp_line
			(start -2.504948 1.633728)
			(end -1.6002 1.633728)
			(stroke
				(width 0.1524)
				(type default)
			)
			(layer "B.SilkS")
		)
		(fp_line
			(start 2.563114 1.633728)
			(end 1.6002 1.633728)
			(stroke
				(width 0.1524)
				(type default)
			)
			(layer "B.SilkS")
		)
		(fp_line
			(start -2.504948 -1.616456)
			(end -2.504948 1.633728)
			(stroke
				(width 0.1524)
				(type default)
			)
			(layer "B.SilkS")
		)
		(fp_line
			(start -1.6002 -1.616456)
			(end -2.504948 -1.616456)
			(stroke
				(width 0.1524)
				(type default)
			)
			(layer "B.SilkS")
		)
		(fp_line
			(start 1.6002 -1.616456)
			(end 2.563114 -1.616456)
			(stroke
				(width 0.1524)
				(type default)
			)
			(layer "B.SilkS")
		)
		(fp_line
			(start 2.563114 -1.616456)
			(end 2.563114 1.633728)
			(stroke
				(width 0.1524)
				(type default)
			)
			(layer "B.SilkS")
		)
		(fp_rect
			(start 2.286 7.366)
			(end -2.286 -0.254)
			(stroke
				(width 0)
				(type default)
			)
			(fill no)
			(layer "B.CrtYd")
		)
		(fp_line
			(start -2.286 7.366)
			(end 2.286 7.366)
			(stroke
				(width 0.1)
				(type default)
			)
			(layer "B.Fab")
		)
		(fp_line
			(start 2.286 7.366)
			(end 2.286 -0.254)
			(stroke
				(width 0.1)
				(type default)
			)
			(layer "B.Fab")
		)
		(fp_line
			(start -2.286 -0.254)
			(end -2.286 7.366)
			(stroke
				(width 0.1)
				(type default)
			)
			(layer "B.Fab")
		)
		(fp_line
			(start 2.286 -0.254)
			(end -2.286 -0.254)
			(stroke
				(width 0.1)
				(type default)
			)
			(layer "B.Fab")
		)
		(pad "1" smd rect
			(at 0 0 90)
			(size 2.54 3.048)
			(layers "B.Cu" "B.Mask" "B.Paste")
			(net "PVCCIN_CPU0")
		)
		(pad "2" smd rect
			(at 0 7.112 90)
			(size 2.54 3.048)
			(layers "B.Cu" "B.Mask" "B.Paste")
			(net "GND")
		)
	)
	(footprint ""
		(layer "B.Cu")
		(at 4.3942 -115.65382)
		(property "Reference" "Q1B1"
			(at -1.310894 -2.428748 180)
			(unlocked yes)
			(layer "B.SilkS")
			(effects
				(font
					(size 0.7874 0.5842)
					(thickness 0.1524)
				)
				(justify left mirror)
			)
		)
		(property "Value" ""
			(at 0 0 0)
			(layer "B.Fab")
			(effects
				(font
					(size 1.27 1.27)
				)
				(justify mirror)
			)
		)
		(duplicate_pad_numbers_are_jumpers no)
		(fp_line
			(start 0.245364 -1.379982)
			(end -3.15468 -1.379982)
			(stroke
				(width 0.1524)
				(type default)
			)
			(layer "B.SilkS")
		)
		(fp_line
			(start 0.245364 2.020062)
			(end -3.15468 2.020062)
			(stroke
				(width 0.1524)
				(type default)
			)
			(layer "B.SilkS")
		)
		(fp_circle
			(center 0.36703 -1.740408)
			(end 0.49403 -1.740408)
			(stroke
				(width 0.254)
				(type default)
			)
			(fill no)
			(layer "B.SilkS")
		)
		(fp_poly
			(pts
				(xy -0.890016 -0.82296) (xy -0.890016 1.46304) (xy -3.404616 1.46304) (xy -3.404616 1.13284) (xy -2.617216 1.13284)
				(xy -2.617216 0.811022) (xy -3.404616 0.811022) (xy -3.404616 0.480822) (xy -2.617216 0.480822)
				(xy -2.617216 0.159258) (xy -3.404616 0.159258) (xy -3.404616 -0.170942) (xy -2.617216 -0.170942)
				(xy -2.617216 -0.49276) (xy -3.404616 -0.49276) (xy -3.404616 -0.82296)
			)
			(stroke
				(width 0)
				(type default)
			)
			(fill yes)
			(layer "B.Paste")
		)
		(fp_poly
			(pts
				(xy 0.245364 -1.379982) (xy 0.245364 2.020062) (xy -3.15468 2.020062) (xy -3.15468 -1.379982)
			)
			(stroke
				(width 0)
				(type default)
			)
			(fill no)
			(layer "B.CrtYd")
		)
		(fp_line
			(start -3.15468 -1.379982)
			(end -3.15468 2.020062)
			(stroke
				(width 0.1)
				(type default)
			)
			(layer "B.Fab")
		)
		(fp_line
			(start -3.15468 2.020062)
			(end 0.245364 2.020062)
			(stroke
				(width 0.1)
				(type default)
			)
			(layer "B.Fab")
		)
		(fp_line
			(start 0.245364 -1.379982)
			(end -3.15468 -1.379982)
			(stroke
				(width 0.1)
				(type default)
			)
			(layer "B.Fab")
		)
		(fp_line
			(start 0.245364 2.020062)
			(end 0.245364 -1.379982)
			(stroke
				(width 0.1)
				(type default)
			)
			(layer "B.Fab")
		)
		(fp_circle
			(center 0.94996 -1.512316)
			(end 1.07696 -1.512316)
			(stroke
				(width 0.254)
				(type default)
			)
			(fill no)
			(layer "B.Fab")
		)
		(pad "1" smd custom
			(at 0 0 180)
			(size 0.24765 0.24765)
			(layers "B.Cu" "B.Mask" "B.Paste")
			(net "P12V_FAN")
			(options
				(clearance outline)
				(anchor circle)
			)
			(primitives
				(gr_poly
					(pts
						(xy 0.4953 -0.8255) (xy 0.4953 0.8255) (xy -0.4953 0.8255) (xy -0.4953 0.4953) (xy 0.0127 0.4953)
						(xy 0.0127 0.1651) (xy -0.4953 0.1651) (xy -0.4953 -0.1651) (xy 0.0127 -0.1651) (xy 0.0127 -0.4953)
						(xy -0.4953 -0.4953) (xy -0.4953 -0.8255)
					)
					(width 0)
					(fill yes)
				)
			)
		)
		(pad "4" smd rect
			(at 0 1.30048 180)
			(size 0.9906 0.3302)
			(layers "B.Cu" "B.Mask" "B.Paste")
			(net "P12V_FAN_SWITCH_G")
		)
		(pad "5" smd custom
			(at -2.147316 0.32004 180)
			(size 0.5715 0.5715)
			(layers "B.Cu" "B.Mask" "B.Paste")
			(net "P12V_STBY")
			(options
				(clearance outline)
				(anchor circle)
			)
			(primitives
				(gr_poly
					(pts
						(xy -1.2573 1.143) (xy -1.2573 -1.143) (xy 1.2573 -1.143) (xy 1.2573 -0.8128) (xy 0.4699 -0.8128)
						(xy 0.4699 -0.490982) (xy 1.2573 -0.490982) (xy 1.2573 -0.160782) (xy 0.4699 -0.160782) (xy 0.4699 0.160782)
						(xy 1.2573 0.160782) (xy 1.2573 0.490982) (xy 0.4699 0.490982) (xy 0.4699 0.8128) (xy 1.2573 0.8128)
						(xy 1.2573 1.143)
					)
					(width 0)
					(fill yes)
				)
			)
		)
	)
	(footprint ""
		(layer "B.Cu")
		(at 114.046254 -79.60614 180)
		(property "Reference" "C7P4"
			(at 0 0 0)
			(layer "B.SilkS")
			(hide yes)
			(effects
				(font
					(size 1.27 1.27)
				)
				(justify mirror)
			)
		)
		(property "Value" ""
			(at 0 0 0)
			(layer "B.Fab")
			(effects
				(font
					(size 1.27 1.27)
				)
				(justify mirror)
			)
		)
		(duplicate_pad_numbers_are_jumpers no)
		(fp_poly
			(pts
				(xy 0.7239 -0.2159) (xy -0.7239 -0.2159) (xy -0.7239 1.9939) (xy 0.7239 1.9939)
			)
			(stroke
				(width 0)
				(type default)
			)
			(fill no)
			(layer "B.CrtYd")
		)
		(fp_line
			(start 0.7239 1.9939)
			(end -0.7239 1.9939)
			(stroke
				(width 0.1)
				(type default)
			)
			(layer "B.Fab")
		)
		(fp_line
			(start 0.7239 -0.2159)
			(end 0.7239 1.9939)
			(stroke
				(width 0.1)
				(type default)
			)
			(layer "B.Fab")
		)
		(fp_line
			(start -0.7239 1.9939)
			(end -0.7239 -0.2159)
			(stroke
				(width 0.1)
				(type default)
			)
			(layer "B.Fab")
		)
		(fp_line
			(start -0.7239 -0.2159)
			(end 0.7239 -0.2159)
			(stroke
				(width 0.1)
				(type default)
			)
			(layer "B.Fab")
		)
		(pad "1" smd rect
			(at 0 0)
			(size 1.27 1.016)
			(layers "B.Cu" "B.Mask" "B.Paste")
			(net "PVCCMCP_CPU1")
		)
		(pad "2" smd rect
			(at 0 1.778)
			(size 1.27 1.016)
			(layers "B.Cu" "B.Mask" "B.Paste")
			(net "GND")
		)
		(zone
			(layer "B.Cu")
			(hatch none 0.5)
			(connect_pads
				(clearance 0)
			)
			(min_thickness 0.25)
			(keepout
				(tracks not_allowed)
				(vias allowed)
				(pads allowed)
				(copperpour not_allowed)
				(footprints allowed)
			)
			(placement
				(enabled no)
				(sheetname "")
			)
			(fill
				(thermal_gap 0.5)
				(thermal_bridge_width 0.5)
				(island_removal_mode 0)
			)
			(polygon
				(pts
					(xy 113.411254 -80.11414) (xy 114.681254 -80.11414) (xy 114.681254 -80.87614) (xy 113.411254 -80.87614)
				)
			)
		)
	)
	(footprint ""
		(layer "B.Cu")
		(at 442.262006 -43.54195 180)
		(property "Reference" "R25W40"
			(at 0 0 0)
			(layer "B.SilkS")
			(hide yes)
			(effects
				(font
					(size 1.27 1.27)
				)
				(justify mirror)
			)
		)
		(property "Value" "*"
			(at -0.064008 -4.108196 180)
			(unlocked yes)
			(layer "B.Fab")
			(hide yes)
			(effects
				(font
					(size 1.27 1.016)
					(thickness 0.1524)
				)
				(justify mirror)
			)
		)
		(property "Device Type" "120R2F-GP_RCL_GP-120R2F-GP,64.A"
			(at -0.064008 -5.632196 180)
			(unlocked yes)
			(layer "B.Fab")
			(hide yes)
			(effects
				(font
					(size 1.27 1.016)
					(thickness 0.1524)
				)
				(justify mirror)
			)
		)
		(duplicate_pad_numbers_are_jumpers no)
		(fp_line
			(start 0.508 -0.9398)
			(end 0.508 0.9398)
			(stroke
				(width 0.1524)
				(type default)
			)
			(layer "B.SilkS")
		)
		(fp_line
			(start -0.508 -0.9398)
			(end 0.508 -0.9398)
			(stroke
				(width 0.1524)
				(type default)
			)
			(layer "B.SilkS")
		)
		(fp_rect
			(start 0.508 0.9398)
			(end -0.508 -0.9398)
			(stroke
				(width 0)
				(type default)
			)
			(fill no)
			(layer "B.CrtYd")
		)
		(fp_rect
			(start 0.508 0.9398)
			(end -0.508 -0.9398)
			(stroke
				(width 0)
				(type default)
			)
			(fill no)
			(layer "B.Fab")
		)
		(pad "1" smd custom
			(at 0 -0.4445)
			(size 0.1397 0.1397)
			(layers "B.Cu" "B.Mask" "B.Paste")
			(net "BMC_M_A2")
			(options
				(clearance outline)
				(anchor circle)
			)
			(primitives
				(gr_poly
					(pts
						(arc
							(start -0.1778 0.2794)
							(mid -0.249642 0.249642)
							(end -0.2794 0.1778)
						)
						(arc
							(start -0.2794 -0.1778)
							(mid -0.249642 -0.249642)
							(end -0.1778 -0.2794)
						)
						(arc
							(start 0.1778 -0.2794)
							(mid 0.249642 -0.249642)
							(end 0.2794 -0.1778)
						)
						(arc
							(start 0.2794 0.1778)
							(mid 0.249642 0.249642)
							(end 0.1778 0.2794)
						)
					)
					(width 0)
					(fill yes)
				)
			)
		)
		(pad "2" smd custom
			(at 0 0.4445)
			(size 0.1397 0.1397)
			(layers "B.Cu" "B.Mask" "B.Paste")
			(net "P1V2_AUX_BMC")
			(options
				(clearance outline)
				(anchor circle)
			)
			(primitives
				(gr_poly
					(pts
						(arc
							(start -0.1778 0.2794)
							(mid -0.249642 0.249642)
							(end -0.2794 0.1778)
						)
						(arc
							(start -0.2794 -0.1778)
							(mid -0.249642 -0.249642)
							(end -0.1778 -0.2794)
						)
						(arc
							(start 0.1778 -0.2794)
							(mid 0.249642 -0.249642)
							(end 0.2794 -0.1778)
						)
						(arc
							(start 0.2794 0.1778)
							(mid 0.249642 0.249642)
							(end 0.1778 0.2794)
						)
					)
					(width 0)
					(fill yes)
				)
			)
		)
	)
	(footprint ""
		(layer "B.Cu")
		(at 309.436516 -28.944824)
		(property "Reference" "R8W9"
			(at 0.8382 -0.67818 0)
			(unlocked yes)
			(layer "B.SilkS")
			(effects
				(font
					(size 0.4064 0.254)
					(thickness 0.1524)
				)
				(justify left mirror)
			)
		)
		(property "Value" ""
			(at 0 0 0)
			(layer "B.Fab")
			(effects
				(font
					(size 1.27 1.27)
				)
				(justify mirror)
			)
		)
		(duplicate_pad_numbers_are_jumpers no)
		(fp_poly
			(pts
				(xy 0.2794 -0.1016) (xy -0.2794 -0.1016) (xy -0.2794 0.9906) (xy 0.2794 0.9906)
			)
			(stroke
				(width 0)
				(type default)
			)
			(fill no)
			(layer "B.CrtYd")
		)
		(fp_line
			(start -0.2794 -0.1016)
			(end 0.2794 -0.1016)
			(stroke
				(width 0.1)
				(type default)
			)
			(layer "B.Fab")
		)
		(fp_line
			(start -0.2794 0.9906)
			(end -0.2794 -0.1016)
			(stroke
				(width 0.1)
				(type default)
			)
			(layer "B.Fab")
		)
		(fp_line
			(start 0.2794 -0.1016)
			(end 0.2794 0.9906)
			(stroke
				(width 0.1)
				(type default)
			)
			(layer "B.Fab")
		)
		(fp_line
			(start 0.2794 0.9906)
			(end -0.2794 0.9906)
			(stroke
				(width 0.1)
				(type default)
			)
			(layer "B.Fab")
		)
		(pad "1" smd rect
			(at 0 0 180)
			(size 0.508 0.508)
			(layers "B.Cu" "B.Mask" "B.Paste")
			(net "P3V3_STBY")
		)
		(pad "2" smd rect
			(at 0 0.889 180)
			(size 0.508 0.508)
			(layers "B.Cu" "B.Mask" "B.Paste")
			(net "IRQ_DIMM_SAVE_LVT3_CPU1")
		)
		(zone
			(layer "B.Cu")
			(hatch none 0.5)
			(connect_pads
				(clearance 0)
			)
			(min_thickness 0.25)
			(keepout
				(tracks allowed)
				(vias not_allowed)
				(pads allowed)
				(copperpour not_allowed)
				(footprints allowed)
			)
			(placement
				(enabled no)
				(sheetname "")
			)
			(fill
				(thermal_gap 0.5)
				(thermal_bridge_width 0.5)
				(island_removal_mode 0)
			)
			(polygon
				(pts
					(xy 309.690516 -28.690824) (xy 309.182516 -28.690824) (xy 309.182516 -28.309824) (xy 309.690516 -28.309824)
				)
			)
		)
		(zone
			(layer "B.Cu")
			(hatch none 0.5)
			(connect_pads
				(clearance 0)
			)
			(min_thickness 0.25)
			(keepout
				(tracks not_allowed)
				(vias allowed)
				(pads allowed)
				(copperpour not_allowed)
				(footprints allowed)
			)
			(placement
				(enabled no)
				(sheetname "")
			)
			(fill
				(thermal_gap 0.5)
				(thermal_bridge_width 0.5)
				(island_removal_mode 0)
			)
			(polygon
				(pts
					(xy 309.690516 -28.309824) (xy 309.182516 -28.309824) (xy 309.182516 -28.690824) (xy 309.690516 -28.690824)
				)
			)
		)
	)
	(footprint ""
		(layer "B.Cu")
		(at 491.41888 -132.1816 180)
		(property "Reference" "R6W50"
			(at 0.8382 -0.67818 180)
			(unlocked yes)
			(layer "B.SilkS")
			(effects
				(font
					(size 0.4064 0.254)
					(thickness 0.1524)
				)
				(justify left mirror)
			)
		)
		(property "Value" ""
			(at 0 0 0)
			(layer "B.Fab")
			(effects
				(font
					(size 1.27 1.27)
				)
				(justify mirror)
			)
		)
		(duplicate_pad_numbers_are_jumpers no)
		(fp_poly
			(pts
				(xy 0.2794 -0.1016) (xy -0.2794 -0.1016) (xy -0.2794 0.9906) (xy 0.2794 0.9906)
			)
			(stroke
				(width 0)
				(type default)
			)
			(fill no)
			(layer "B.CrtYd")
		)
		(fp_line
			(start 0.2794 0.9906)
			(end -0.2794 0.9906)
			(stroke
				(width 0.1)
				(type default)
			)
			(layer "B.Fab")
		)
		(fp_line
			(start 0.2794 -0.1016)
			(end 0.2794 0.9906)
			(stroke
				(width 0.1)
				(type default)
			)
			(layer "B.Fab")
		)
		(fp_line
			(start -0.2794 0.9906)
			(end -0.2794 -0.1016)
			(stroke
				(width 0.1)
				(type default)
			)
			(layer "B.Fab")
		)
		(fp_line
			(start -0.2794 -0.1016)
			(end 0.2794 -0.1016)
			(stroke
				(width 0.1)
				(type default)
			)
			(layer "B.Fab")
		)
		(pad "1" smd rect
			(at 0 0)
			(size 0.508 0.508)
			(layers "B.Cu" "B.Mask" "B.Paste")
			(net "P3V3_STBY")
		)
		(pad "2" smd rect
			(at 0 0.889)
			(size 0.508 0.508)
			(layers "B.Cu" "B.Mask" "B.Paste")
			(net "SPA_MID_DBG2_RX")
		)
		(zone
			(layer "B.Cu")
			(hatch none 0.5)
			(connect_pads
				(clearance 0)
			)
			(min_thickness 0.25)
			(keepout
				(tracks not_allowed)
				(vias allowed)
				(pads allowed)
				(copperpour not_allowed)
				(footprints allowed)
			)
			(placement
				(enabled no)
				(sheetname "")
			)
			(fill
				(thermal_gap 0.5)
				(thermal_bridge_width 0.5)
				(island_removal_mode 0)
			)
			(polygon
				(pts
					(xy 491.16488 -132.8166) (xy 491.67288 -132.8166) (xy 491.67288 -132.4356) (xy 491.16488 -132.4356)
				)
			)
		)
		(zone
			(layer "B.Cu")
			(hatch none 0.5)
			(connect_pads
				(clearance 0)
			)
			(min_thickness 0.25)
			(keepout
				(tracks allowed)
				(vias not_allowed)
				(pads allowed)
				(copperpour not_allowed)
				(footprints allowed)
			)
			(placement
				(enabled no)
				(sheetname "")
			)
			(fill
				(thermal_gap 0.5)
				(thermal_bridge_width 0.5)
				(island_removal_mode 0)
			)
			(polygon
				(pts
					(xy 491.16488 -132.4356) (xy 491.67288 -132.4356) (xy 491.67288 -132.8166) (xy 491.16488 -132.8166)
				)
			)
		)
	)
)
